(kicad_pcb
	(version 20260206)
	(generator "pcbnew")
	(generator_version "10.0")
	(general
		(thickness 1.6)
		(legacy_teardrops no)
	)
	(paper "A4")
	(title_block
		(title "Wiwynn_Tioga_Pass_MB.brd")
		(comment 1 "Tioga Pass / footprint 2254 of 4770 (U5D1), pads 411-520 of 3647")
	)
	(layers
		(0 "F.Cu" signal "TOP")
		(4 "In1.Cu" signal "L2GND")
		(6 "In2.Cu" signal "L3")
		(8 "In3.Cu" signal "L4GND")
		(10 "In4.Cu" signal "L5")
		(12 "In5.Cu" signal "L6GND")
		(14 "In6.Cu" signal "L7VCC")
		(16 "In7.Cu" signal "L8VCC")
		(18 "In8.Cu" signal "L9GND")
		(20 "In9.Cu" signal "L10")
		(22 "In10.Cu" signal "L11GND")
		(24 "In11.Cu" signal "L12")
		(26 "In12.Cu" signal "L13GND")
		(2 "B.Cu" signal "BOTTOM")
		(9 "F.Adhes" user "F.Adhesive")
		(11 "B.Adhes" user "B.Adhesive")
		(13 "F.Paste" user "Package Geometry/Pastemask Top")
		(15 "B.Paste" user "Package Geometry/Pastemask Bottom")
		(5 "F.SilkS" user "Ref Des/Silkscreen Top")
		(7 "B.SilkS" user "Ref Des/Silkscreen Bottom")
		(1 "F.Mask" user "Board Geometry/Soldermask Top")
		(3 "B.Mask" user "Board Geometry/Soldermask Bottom")
		(17 "Dwgs.User" user "User.Drawings")
		(19 "Cmts.User" user "User.Comments")
		(21 "Eco1.User" user "User.Eco1")
		(23 "Eco2.User" user "User.Eco2")
		(25 "Edge.Cuts" user "Board Geometry/Outline")
		(27 "Margin" user)
		(31 "F.CrtYd" user "Package Geometry/Place Bound Top")
		(29 "B.CrtYd" user "Package Geometry/Place Bound Bottom")
		(35 "F.Fab" user "Ref Des/Assembly Top")
		(33 "B.Fab" user "Ref Des/Assembly Bottom")
	)
	(footprint ""
		(layer "F.Cu")
		(at 270.000222 -76.550012 180)
		(property "Reference" "U5D1"
			(at 19.124422 31.601918 0)
			(unlocked yes)
			(layer "F.SilkS")
			(effects
				(font
					(size 0.7874 0.5842)
					(thickness 0.1524)
				)
			)
		)
		(property "Value" ""
			(at 0 0 180)
			(layer "F.Fab")
			(effects
				(font
					(size 1.27 1.27)
				)
			)
		)
		(duplicate_pad_numbers_are_jumpers no)
		(pad "AK49" smd circle
			(at 5.485892 -12.539726)
			(size 0.4318 0.4318)
			(layers "F.Cu" "F.Mask" "F.Paste")
			(net "PVCCIN_CPU0")
		)
		(pad "AK51" smd circle
			(at 7.202932 -12.539726)
			(size 0.4318 0.4318)
			(layers "F.Cu" "F.Mask" "F.Paste")
			(net "PVCCIN_CPU0")
		)
		(pad "AK53" smd circle
			(at 8.919972 -12.539726)
			(size 0.4318 0.4318)
			(layers "F.Cu" "F.Mask" "F.Paste")
			(net "PVCCIN_CPU0")
		)
		(pad "AK55" smd circle
			(at 10.637012 -12.539726)
			(size 0.4318 0.4318)
			(layers "F.Cu" "F.Mask" "F.Paste")
			(net "GND")
		)
		(pad "AK57" smd circle
			(at 12.354052 -12.539726)
			(size 0.4318 0.4318)
			(layers "F.Cu" "F.Mask" "F.Paste")
			(net "TP_CPU0_RSVD_219")
		)
		(pad "AK59" smd circle
			(at 14.071092 -12.539726)
			(size 0.4318 0.4318)
			(layers "F.Cu" "F.Mask" "F.Paste")
			(net "TP_CPU0_RSVD_218")
		)
		(pad "AK61" smd circle
			(at 15.787878 -12.539726)
			(size 0.4318 0.4318)
			(layers "F.Cu" "F.Mask" "F.Paste")
			(net "TP_CPU0_RSVD_217")
		)
		(pad "AK63" smd circle
			(at 17.504918 -12.539726)
			(size 0.4318 0.4318)
			(layers "F.Cu" "F.Mask" "F.Paste")
			(net "M_B_CPU_VREF")
		)
		(pad "AK65" smd circle
			(at 19.221958 -12.539726)
			(size 0.4318 0.4318)
			(layers "F.Cu" "F.Mask" "F.Paste")
			(net "GND")
		)
		(pad "AK67" smd circle
			(at 20.938998 -12.539726)
			(size 0.4318 0.4318)
			(layers "F.Cu" "F.Mask" "F.Paste")
			(net "GND")
		)
		(pad "AK69" smd circle
			(at 22.656038 -12.539726)
			(size 0.4318 0.4318)
			(layers "F.Cu" "F.Mask" "F.Paste")
			(net "TP_CPU0_RSVD_216")
		)
		(pad "AK73" smd circle
			(at 26.090118 -12.539726)
			(size 0.4318 0.4318)
			(layers "F.Cu" "F.Mask" "F.Paste")
			(net "GND")
		)
		(pad "AK75" smd circle
			(at 27.806904 -12.539726)
			(size 0.4318 0.4318)
			(layers "F.Cu" "F.Mask" "F.Paste")
			(net "M_C_DQ<7>")
		)
		(pad "AK77" smd circle
			(at 29.523944 -12.539726)
			(size 0.4318 0.4318)
			(layers "F.Cu" "F.Mask" "F.Paste")
			(net "M_C_DQ<2>")
		)
		(pad "AK79" smd circle
			(at 31.240984 -12.539726)
			(size 0.4318 0.4318)
			(layers "F.Cu" "F.Mask" "F.Paste")
			(net "GND")
		)
		(pad "AK81" smd circle
			(at 32.958024 -12.539726)
			(size 0.4318 0.4318)
			(layers "F.Cu" "F.Mask" "F.Paste")
			(net "GND")
		)
		(pad "AK83" smd circle
			(at 34.675064 -12.539726)
			(size 0.4318 0.4318)
			(layers "F.Cu" "F.Mask" "F.Paste")
			(net "GND")
		)
		(pad "AK85" smd circle
			(at 36.392104 -12.539726)
			(size 0.4318 0.4318)
			(layers "F.Cu" "F.Mask" "F.Paste")
			(net "GND")
		)
		(pad "AL2" smd circle
			(at -36.392104 -10.244074)
			(size 0.4318 0.4318)
			(layers "F.Cu" "F.Mask" "F.Paste")
			(net "UPI_CPU0_CPU1_P0P0_DN<10>")
		)
		(pad "AL4" smd circle
			(at -34.675064 -10.244074)
			(size 0.4318 0.4318)
			(layers "F.Cu" "F.Mask" "F.Paste")
			(net "GND")
		)
		(pad "AL6" smd circle
			(at -32.958024 -10.244074)
			(size 0.4318 0.4318)
			(layers "F.Cu" "F.Mask" "F.Paste")
			(net "UPI_CPU1_CPU0_P0P0_DN<12>")
		)
		(pad "AL8" smd circle
			(at -31.240984 -10.244074)
			(size 0.4318 0.4318)
			(layers "F.Cu" "F.Mask" "F.Paste")
			(net "UPI_CPU1_CPU0_P0P0_DP<10>")
		)
		(pad "AL10" smd circle
			(at -29.523944 -10.244074)
			(size 0.4318 0.4318)
			(layers "F.Cu" "F.Mask" "F.Paste")
			(net "GND")
		)
		(pad "AL12" smd circle
			(at -27.806904 -10.244074)
			(size 0.4318 0.4318)
			(layers "F.Cu" "F.Mask" "F.Paste")
			(net "H_CPU0_ERR2_G_N")
		)
		(pad "AL14" smd circle
			(at -26.090118 -10.244074)
			(size 0.4318 0.4318)
			(layers "F.Cu" "F.Mask" "F.Paste")
			(net "H_CPU0_CATERR_G_N")
		)
		(pad "AL18" smd circle
			(at -22.656038 -10.244074)
			(size 0.4318 0.4318)
			(layers "F.Cu" "F.Mask" "F.Paste")
			(net "SMB_CPU0_PE_HP_GTL_SDA")
		)
		(pad "AL20" smd circle
			(at -20.938998 -10.244074)
			(size 0.4318 0.4318)
			(layers "F.Cu" "F.Mask" "F.Paste")
			(net "VSENSE_P1V8MCP_CPU0_SKT_VRTN")
		)
		(pad "AL22" smd circle
			(at -19.221958 -10.244074)
			(size 0.4318 0.4318)
			(layers "F.Cu" "F.Mask" "F.Paste")
			(net "TP_CPU0_RSVD_214")
		)
		(pad "AL24" smd circle
			(at -17.504918 -10.244074)
			(size 0.4318 0.4318)
			(layers "F.Cu" "F.Mask" "F.Paste")
			(net "GND")
		)
		(pad "AL26" smd circle
			(at -15.787878 -10.244074)
			(size 0.4318 0.4318)
			(layers "F.Cu" "F.Mask" "F.Paste")
			(net "CLK_322M_OSC_CPU0_RC_DN")
		)
		(pad "AL28" smd circle
			(at -14.071092 -10.244074)
			(size 0.4318 0.4318)
			(layers "F.Cu" "F.Mask" "F.Paste")
			(net "PVCCIO_CPU0")
		)
		(pad "AL30" smd circle
			(at -12.354052 -10.244074)
			(size 0.4318 0.4318)
			(layers "F.Cu" "F.Mask" "F.Paste")
			(net "GND")
		)
		(pad "AL32" smd circle
			(at -10.637012 -10.244074)
			(size 0.4318 0.4318)
			(layers "F.Cu" "F.Mask" "F.Paste")
			(net "GND")
		)
		(pad "AL34" smd circle
			(at -8.919972 -10.244074)
			(size 0.4318 0.4318)
			(layers "F.Cu" "F.Mask" "F.Paste")
			(net "PVCCIN_CPU0")
		)
		(pad "AL46" smd circle
			(at 2.910586 -12.044172)
			(size 0.508 0.508)
			(layers "F.Cu" "F.Mask" "F.Paste")
			(net "PVCCIN_CPU0")
		)
		(pad "AL48" smd circle
			(at 4.627626 -12.044172)
			(size 0.508 0.508)
			(layers "F.Cu" "F.Mask" "F.Paste")
			(net "PVCCIN_CPU0")
		)
		(pad "AL50" smd circle
			(at 6.344412 -12.044172)
			(size 0.508 0.508)
			(layers "F.Cu" "F.Mask" "F.Paste")
			(net "PVCCIN_CPU0")
		)
		(pad "AL52" smd circle
			(at 8.061452 -12.044172)
			(size 0.508 0.508)
			(layers "F.Cu" "F.Mask" "F.Paste")
			(net "PVCCIN_CPU0")
		)
		(pad "AL54" smd circle
			(at 9.778492 -12.044172)
			(size 0.4318 0.4318)
			(layers "F.Cu" "F.Mask" "F.Paste")
			(net "PVCCIN_CPU0")
		)
		(pad "AL56" smd circle
			(at 11.495532 -12.044172)
			(size 0.4318 0.4318)
			(layers "F.Cu" "F.Mask" "F.Paste")
			(net "GND")
		)
		(pad "AL58" smd circle
			(at 13.212572 -12.044172)
			(size 0.4318 0.4318)
			(layers "F.Cu" "F.Mask" "F.Paste")
			(net "TP_CPU0_RSVD_212")
		)
		(pad "AL60" smd circle
			(at 14.929612 -12.044172)
			(size 0.4318 0.4318)
			(layers "F.Cu" "F.Mask" "F.Paste")
			(net "TP_CPU0_RSVD_211")
		)
		(pad "AL62" smd circle
			(at 16.646398 -12.044172)
			(size 0.4318 0.4318)
			(layers "F.Cu" "F.Mask" "F.Paste")
			(net "TP_CPU0_RSVD_210")
		)
		(pad "AL64" smd circle
			(at 18.363438 -12.044172)
			(size 0.4318 0.4318)
			(layers "F.Cu" "F.Mask" "F.Paste")
			(net "GND")
		)
		(pad "AL66" smd circle
			(at 20.080478 -12.044172)
			(size 0.4318 0.4318)
			(layers "F.Cu" "F.Mask" "F.Paste")
			(net "M_C_DQS_DN<12>")
		)
		(pad "AL68" smd circle
			(at 21.797518 -12.044172)
			(size 0.4318 0.4318)
			(layers "F.Cu" "F.Mask" "F.Paste")
			(net "GND")
		)
		(pad "AL74" smd circle
			(at 26.948384 -12.044172)
			(size 0.4318 0.4318)
			(layers "F.Cu" "F.Mask" "F.Paste")
			(net "M_C_DQS_DN<0>")
		)
		(pad "AL76" smd circle
			(at 28.665424 -12.044172)
			(size 0.4318 0.4318)
			(layers "F.Cu" "F.Mask" "F.Paste")
			(net "GND")
		)
		(pad "AL78" smd circle
			(at 30.382464 -12.044172)
			(size 0.4318 0.4318)
			(layers "F.Cu" "F.Mask" "F.Paste")
			(net "GND")
		)
		(pad "AL80" smd circle
			(at 32.099504 -12.044172)
			(size 0.4318 0.4318)
			(layers "F.Cu" "F.Mask" "F.Paste")
			(net "GND")
		)
		(pad "AL82" smd circle
			(at 33.816544 -12.044172)
			(size 0.4318 0.4318)
			(layers "F.Cu" "F.Mask" "F.Paste")
			(net "GND")
		)
		(pad "AL84" smd circle
			(at 35.533584 -12.044172)
			(size 0.4318 0.4318)
			(layers "F.Cu" "F.Mask" "F.Paste")
			(net "M_A_DQS_DN<9>")
		)
		(pad "AL86" smd custom
			(at 37.250624 -12.044172 270)
			(size 0.10795 0.10795)
			(layers "F.Cu" "F.Mask" "F.Paste")
			(net "GND")
			(options
				(clearance outline)
				(anchor circle)
			)
			(primitives
				(gr_poly
					(pts
						(arc
							(start 0.2159 -0.0381)
							(mid 0 -0.254)
							(end -0.2159 -0.0381)
						)
						(arc
							(start -0.2159 0.0381)
							(mid 0 0.254)
							(end 0.2159 0.0381)
						)
					)
					(width 0)
					(fill yes)
				)
			)
		)
		(pad "AM1" smd custom
			(at -37.250624 -9.749028 90)
			(size 0.10795 0.10795)
			(layers "F.Cu" "F.Mask" "F.Paste")
			(net "GND")
			(options
				(clearance outline)
				(anchor circle)
			)
			(primitives
				(gr_poly
					(pts
						(arc
							(start 0.2159 -0.0381)
							(mid 0 -0.254)
							(end -0.2159 -0.0381)
						)
						(arc
							(start -0.2159 0.0381)
							(mid 0 0.254)
							(end 0.2159 0.0381)
						)
					)
					(width 0)
					(fill yes)
				)
			)
		)
		(pad "AM3" smd circle
			(at -35.533584 -9.749028)
			(size 0.4318 0.4318)
			(layers "F.Cu" "F.Mask" "F.Paste")
			(net "UPI_CPU0_CPU1_P0P0_DN<9>")
		)
		(pad "AM5" smd circle
			(at -33.816544 -9.749028)
			(size 0.4318 0.4318)
			(layers "F.Cu" "F.Mask" "F.Paste")
			(net "PVCCIO_CPU0")
		)
		(pad "AM7" smd circle
			(at -32.099504 -9.749028)
			(size 0.4318 0.4318)
			(layers "F.Cu" "F.Mask" "F.Paste")
			(net "UPI_CPU1_CPU0_P0P0_DP<11>")
		)
		(pad "AM9" smd circle
			(at -30.382464 -9.749028)
			(size 0.4318 0.4318)
			(layers "F.Cu" "F.Mask" "F.Paste")
			(net "UPI_CPU1_CPU0_P0P0_DN<10>")
		)
		(pad "AM11" smd circle
			(at -28.665424 -9.749028)
			(size 0.4318 0.4318)
			(layers "F.Cu" "F.Mask" "F.Paste")
			(net "PU_CPU0_TSC_SYNC")
		)
		(pad "AM13" smd circle
			(at -26.948384 -9.749028)
			(size 0.4318 0.4318)
			(layers "F.Cu" "F.Mask" "F.Paste")
			(net "TP_CPU0_RSVD_TEST_3")
		)
		(pad "AM19" smd circle
			(at -21.797518 -9.749028)
			(size 0.4318 0.4318)
			(layers "F.Cu" "F.Mask" "F.Paste")
			(net "SMB_CPU0_PE_HP_GTL_SCL")
		)
		(pad "AM21" smd circle
			(at -20.080478 -9.749028)
			(size 0.4318 0.4318)
			(layers "F.Cu" "F.Mask" "F.Paste")
			(net "PVCCMCP_CPU0")
		)
		(pad "AM23" smd circle
			(at -18.363438 -9.749028)
			(size 0.4318 0.4318)
			(layers "F.Cu" "F.Mask" "F.Paste")
			(net "TP_CPU0_RSVD_208")
		)
		(pad "AM25" smd circle
			(at -16.646398 -9.749028)
			(size 0.4318 0.4318)
			(layers "F.Cu" "F.Mask" "F.Paste")
			(net "PVCCMCP_CPU0")
		)
		(pad "AM27" smd circle
			(at -14.929612 -9.749028)
			(size 0.4318 0.4318)
			(layers "F.Cu" "F.Mask" "F.Paste")
			(net "CLK_100M_CPU0_RC_REFCLK0_DP")
		)
		(pad "AM29" smd circle
			(at -13.212572 -9.749028)
			(size 0.4318 0.4318)
			(layers "F.Cu" "F.Mask" "F.Paste")
			(net "PVCCIO_CPU0")
		)
		(pad "AM31" smd circle
			(at -11.495532 -9.749028)
			(size 0.4318 0.4318)
			(layers "F.Cu" "F.Mask" "F.Paste")
			(net "GND")
		)
		(pad "AM33" smd circle
			(at -9.778492 -9.749028)
			(size 0.4318 0.4318)
			(layers "F.Cu" "F.Mask" "F.Paste")
			(net "PVCCIN_CPU0")
		)
		(pad "AM53" smd circle
			(at 8.919972 -11.549126)
			(size 0.508 0.508)
			(layers "F.Cu" "F.Mask" "F.Paste")
			(net "PVCCIN_CPU0")
		)
		(pad "AM55" smd circle
			(at 10.637012 -11.549126)
			(size 0.4318 0.4318)
			(layers "F.Cu" "F.Mask" "F.Paste")
			(net "PVCCIN_CPU0")
		)
		(pad "AM57" smd circle
			(at 12.354052 -11.549126)
			(size 0.4318 0.4318)
			(layers "F.Cu" "F.Mask" "F.Paste")
			(net "GND")
		)
		(pad "AM59" smd circle
			(at 14.071092 -11.549126)
			(size 0.4318 0.4318)
			(layers "F.Cu" "F.Mask" "F.Paste")
			(net "TP_CPU0_RSVD_205")
		)
		(pad "AM61" smd circle
			(at 15.787878 -11.549126)
			(size 0.4318 0.4318)
			(layers "F.Cu" "F.Mask" "F.Paste")
			(net "TP_CPU0_RSVD_204")
		)
		(pad "AM63" smd circle
			(at 17.504918 -11.549126)
			(size 0.4318 0.4318)
			(layers "F.Cu" "F.Mask" "F.Paste")
			(net "GND")
		)
		(pad "AM65" smd circle
			(at 19.221958 -11.549126)
			(size 0.4318 0.4318)
			(layers "F.Cu" "F.Mask" "F.Paste")
			(net "M_C_DQ<30>")
		)
		(pad "AM67" smd circle
			(at 20.938998 -11.549126)
			(size 0.4318 0.4318)
			(layers "F.Cu" "F.Mask" "F.Paste")
			(net "M_C_DQ<24>")
		)
		(pad "AM69" smd circle
			(at 22.656038 -11.549126)
			(size 0.4318 0.4318)
			(layers "F.Cu" "F.Mask" "F.Paste")
			(net "GND")
		)
		(pad "AM73" smd circle
			(at 26.090118 -11.549126)
			(size 0.4318 0.4318)
			(layers "F.Cu" "F.Mask" "F.Paste")
			(net "GND")
		)
		(pad "AM75" smd circle
			(at 27.806904 -11.549126)
			(size 0.4318 0.4318)
			(layers "F.Cu" "F.Mask" "F.Paste")
			(net "M_C_DQS_DP<0>")
		)
		(pad "AM77" smd circle
			(at 29.523944 -11.549126)
			(size 0.4318 0.4318)
			(layers "F.Cu" "F.Mask" "F.Paste")
			(net "M_C_DQ<6>")
		)
		(pad "AM79" smd circle
			(at 31.240984 -11.549126)
			(size 0.4318 0.4318)
			(layers "F.Cu" "F.Mask" "F.Paste")
			(net "GND")
		)
		(pad "AM81" smd circle
			(at 32.958024 -11.549126)
			(size 0.4318 0.4318)
			(layers "F.Cu" "F.Mask" "F.Paste")
			(net "M_B_DQ<3>")
		)
		(pad "AM83" smd circle
			(at 34.675064 -11.549126)
			(size 0.4318 0.4318)
			(layers "F.Cu" "F.Mask" "F.Paste")
			(net "GND")
		)
		(pad "AM85" smd circle
			(at 36.392104 -11.549126)
			(size 0.4318 0.4318)
			(layers "F.Cu" "F.Mask" "F.Paste")
			(net "M_A_DQS_DP<9>")
		)
		(pad "AN2" smd circle
			(at -36.392104 -9.253474)
			(size 0.4318 0.4318)
			(layers "F.Cu" "F.Mask" "F.Paste")
			(net "GND")
		)
		(pad "AN4" smd circle
			(at -34.675064 -9.253474)
			(size 0.4318 0.4318)
			(layers "F.Cu" "F.Mask" "F.Paste")
			(net "UPI_CPU0_CPU1_P0P0_DN<8>")
		)
		(pad "AN6" smd circle
			(at -32.958024 -9.253474)
			(size 0.4318 0.4318)
			(layers "F.Cu" "F.Mask" "F.Paste")
			(net "GND")
		)
		(pad "AN8" smd circle
			(at -31.240984 -9.253474)
			(size 0.4318 0.4318)
			(layers "F.Cu" "F.Mask" "F.Paste")
			(net "UPI_CPU1_CPU0_P0P0_DP<9>")
		)
		(pad "AN10" smd circle
			(at -29.523944 -9.253474)
			(size 0.4318 0.4318)
			(layers "F.Cu" "F.Mask" "F.Paste")
			(net "PVCCIO_CPU0")
		)
		(pad "AN12" smd circle
			(at -27.806904 -9.253474)
			(size 0.4318 0.4318)
			(layers "F.Cu" "F.Mask" "F.Paste")
			(net "TP_CPU0_RSVD_TEST_4")
		)
		(pad "AN14" smd circle
			(at -26.090118 -9.253474)
			(size 0.4318 0.4318)
			(layers "F.Cu" "F.Mask" "F.Paste")
			(net "TP_CPU0_RSVD_TEST_5")
		)
		(pad "AN18" smd circle
			(at -22.656038 -9.253474)
			(size 0.4318 0.4318)
			(layers "F.Cu" "F.Mask" "F.Paste")
			(net "PVCCMCP_CPU0")
		)
		(pad "AN20" smd circle
			(at -20.938998 -9.253474)
			(size 0.4318 0.4318)
			(layers "F.Cu" "F.Mask" "F.Paste")
			(net "H_CPU0_MSMI_G_N")
		)
		(pad "AN22" smd circle
			(at -19.221958 -9.253474)
			(size 0.4318 0.4318)
			(layers "F.Cu" "F.Mask" "F.Paste")
			(net "PVCCMCP_CPU0")
		)
		(pad "AN24" smd circle
			(at -17.504918 -9.253474)
			(size 0.4318 0.4318)
			(layers "F.Cu" "F.Mask" "F.Paste")
			(net "PVCCMCP_CPU0")
		)
		(pad "AN26" smd circle
			(at -15.787878 -9.253474)
			(size 0.4318 0.4318)
			(layers "F.Cu" "F.Mask" "F.Paste")
			(net "PVCCMCP_CPU0")
		)
		(pad "AN28" smd circle
			(at -14.071092 -9.253474)
			(size 0.4318 0.4318)
			(layers "F.Cu" "F.Mask" "F.Paste")
			(net "GND")
		)
		(pad "AN30" smd circle
			(at -12.354052 -9.253474)
			(size 0.4318 0.4318)
			(layers "F.Cu" "F.Mask" "F.Paste")
			(net "PWRGD_CPU0_DRAMPWROK_ABC_G")
		)
		(pad "AN32" smd circle
			(at -10.637012 -9.253474)
			(size 0.4318 0.4318)
			(layers "F.Cu" "F.Mask" "F.Paste")
			(net "PVCCIN_CPU0")
		)
		(pad "AN54" smd circle
			(at 9.778492 -11.053572)
			(size 0.508 0.508)
			(layers "F.Cu" "F.Mask" "F.Paste")
			(net "PVCCIN_CPU0")
		)
		(pad "AN56" smd circle
			(at 11.495532 -11.053572)
			(size 0.4318 0.4318)
			(layers "F.Cu" "F.Mask" "F.Paste")
			(net "PVCCIN_CPU0")
		)
		(pad "AN58" smd circle
			(at 13.212572 -11.053572)
			(size 0.4318 0.4318)
			(layers "F.Cu" "F.Mask" "F.Paste")
			(net "GND")
		)
		(pad "AN60" smd circle
			(at 14.929612 -11.053572)
			(size 0.4318 0.4318)
			(layers "F.Cu" "F.Mask" "F.Paste")
			(net "TP_CPU0_RSVD_199")
		)
		(pad "AN62" smd circle
			(at 16.646398 -11.053572)
			(size 0.4318 0.4318)
			(layers "F.Cu" "F.Mask" "F.Paste")
			(net "TP_CPU0_RSVD_198")
		)
		(pad "AN64" smd circle
			(at 18.363438 -11.053572)
			(size 0.4318 0.4318)
			(layers "F.Cu" "F.Mask" "F.Paste")
			(net "M_C_DQ<26>")
		)
		(pad "AN66" smd circle
			(at 20.080478 -11.053572)
			(size 0.4318 0.4318)
			(layers "F.Cu" "F.Mask" "F.Paste")
			(net "M_C_DQS_DP<12>")
		)
		(pad "AN68" smd circle
			(at 21.797518 -11.053572)
			(size 0.4318 0.4318)
			(layers "F.Cu" "F.Mask" "F.Paste")
			(net "M_C_DQ<28>")
		)
		(pad "AN74" smd circle
			(at 26.948384 -11.053572)
			(size 0.4318 0.4318)
			(layers "F.Cu" "F.Mask" "F.Paste")
			(net "M_C_DQ<1>")
		)
		(pad "AN76" smd circle
			(at 28.665424 -11.053572)
			(size 0.4318 0.4318)
			(layers "F.Cu" "F.Mask" "F.Paste")
			(net "M_C_DQS_DP<9>")
		)
		(pad "AN78" smd circle
			(at 30.382464 -11.053572)
			(size 0.4318 0.4318)
			(layers "F.Cu" "F.Mask" "F.Paste")
			(net "GND")
		)
	)
)
